# S9S_MB_2U (Grand Teton) — schematic netlist excerpt (pin names and nets, part order shuffled) for the footprints in the layout excerpt that follows; sources: Cadence DE-HDL packaged netlist, KiCad conversion of 03242023_DA0F0TMBIJ0_F0T_Motherboard_J_brd_V01_OCP.brd

R1600  Q_RES  33.2 1% CHIP  pkg 0402LF  page 183 : A = IRQ_SML0_ALERT_N ; B = IRQ_SML0_ALERT_R_N
R3722  Q_RES  0 5% CHIP  pkg 0402LF  page 233 : A = SMB_LM75_3_3V3AUX_SDA_R ; B = SMB_LM75_3_3V3AUX_SDA

(kicad_pcb
	(version 20260206)
	(generator "pcbnew")
	(generator_version "10.0")
	(general
		(thickness 1.6)
		(legacy_teardrops no)
	)
	(paper "A4")
	(title_block
		(title "03242023_DA0F0TMBIJ0_F0T_Motherboard_J_brd_V01_OCP.brd")
		(comment 1 "Grand Teton / footprints 23-24 of 6105")
	)
	(layers
		(0 "F.Cu" signal "TOP")
		(4 "In1.Cu" signal "GND")
		(6 "In2.Cu" signal "IN1")
		(8 "In3.Cu" signal "GND1")
		(10 "In4.Cu" signal "IN2")
		(12 "In5.Cu" signal "GND2")
		(14 "In6.Cu" signal "IN3")
		(16 "In7.Cu" signal "GND3")
		(18 "In8.Cu" signal "VCC")
		(20 "In9.Cu" signal "VCC1")
		(22 "In10.Cu" signal "GND4")
		(24 "In11.Cu" signal "IN4")
		(26 "In12.Cu" signal "GND5")
		(28 "In13.Cu" signal "IN5")
		(30 "In14.Cu" signal "GND6")
		(32 "In15.Cu" signal "IN6")
		(34 "In16.Cu" signal "GND7")
		(2 "B.Cu" signal "BOTTOM")
		(9 "F.Adhes" user "F.Adhesive")
		(11 "B.Adhes" user "B.Adhesive")
		(13 "F.Paste" user "Package Geometry/Pastemask Top")
		(15 "B.Paste" user "Package Geometry/Pastemask Bottom")
		(5 "F.SilkS" user "Ref Des/Silkscreen Top")
		(7 "B.SilkS" user "Ref Des/Silkscreen Bottom")
		(1 "F.Mask" user "Board Geometry/Soldermask Top")
		(3 "B.Mask" user "Board Geometry/Soldermask Bottom")
		(17 "Dwgs.User" user "User.Drawings")
		(19 "Cmts.User" user "User.Comments")
		(21 "Eco1.User" user "User.Eco1")
		(23 "Eco2.User" user "User.Eco2")
		(25 "Edge.Cuts" user "Board Geometry/Outline")
		(27 "Margin" user)
		(31 "F.CrtYd" user "Package Geometry/Place Bound Top")
		(29 "B.CrtYd" user "Package Geometry/Place Bound Bottom")
		(35 "F.Fab" user "Ref Des/Assembly Top")
		(33 "B.Fab" user "Ref Des/Assembly Bottom")
	)
	(footprint ""
		(layer "F.Cu")
		(at 68.085716 -107.37469)
		(property "Reference" "R3722"
			(at 0 0 0)
			(layer "F.SilkS")
			(hide yes)
			(effects
				(font
					(size 1.27 1.27)
				)
			)
		)
		(property "Value" ""
			(at 0 0 0)
			(layer "F.Fab")
			(effects
				(font
					(size 1.27 1.27)
				)
			)
		)
		(duplicate_pad_numbers_are_jumpers no)
		(fp_line
			(start -0.7874 -0.4064)
			(end 0.7874 -0.4064)
			(stroke
				(width 0.1524)
				(type default)
			)
			(layer "F.SilkS")
		)
		(fp_line
			(start -0.7874 0.4064)
			(end -0.7874 -0.4064)
			(stroke
				(width 0.1524)
				(type default)
			)
			(layer "F.SilkS")
		)
		(fp_line
			(start 0.7874 -0.4064)
			(end 0.7874 0.4064)
			(stroke
				(width 0.1524)
				(type default)
			)
			(layer "F.SilkS")
		)
		(fp_line
			(start 0.7874 0.4064)
			(end -0.7874 0.4064)
			(stroke
				(width 0.1524)
				(type default)
			)
			(layer "F.SilkS")
		)
		(fp_line
			(start -0.67945 -0.305054)
			(end -0.12065 -0.305054)
			(stroke
				(width 0.1)
				(type default)
			)
			(layer "F.Fab")
		)
		(fp_line
			(start -0.67945 0.3048)
			(end -0.67945 -0.305054)
			(stroke
				(width 0.1)
				(type default)
			)
			(layer "F.Fab")
		)
		(fp_line
			(start -0.12065 -0.305054)
			(end -0.12065 -0.2794)
			(stroke
				(width 0.1)
				(type default)
			)
			(layer "F.Fab")
		)
		(fp_line
			(start -0.12065 -0.2794)
			(end 0.12065 -0.2794)
			(stroke
				(width 0.1)
				(type default)
			)
			(layer "F.Fab")
		)
		(fp_line
			(start -0.12065 0.2794)
			(end -0.12065 0.3048)
			(stroke
				(width 0.1)
				(type default)
			)
			(layer "F.Fab")
		)
		(fp_line
			(start -0.12065 0.3048)
			(end -0.67945 0.3048)
			(stroke
				(width 0.1)
				(type default)
			)
			(layer "F.Fab")
		)
		(fp_line
			(start 0.120396 0.2794)
			(end -0.12065 0.2794)
			(stroke
				(width 0.1)
				(type default)
			)
			(layer "F.Fab")
		)
		(fp_line
			(start 0.120396 0.3048)
			(end 0.120396 0.2794)
			(stroke
				(width 0.1)
				(type default)
			)
			(layer "F.Fab")
		)
		(fp_line
			(start 0.12065 -0.3048)
			(end 0.67945 -0.3048)
			(stroke
				(width 0.1)
				(type default)
			)
			(layer "F.Fab")
		)
		(fp_line
			(start 0.12065 -0.2794)
			(end 0.12065 -0.3048)
			(stroke
				(width 0.1)
				(type default)
			)
			(layer "F.Fab")
		)
		(fp_line
			(start 0.67945 -0.3048)
			(end 0.67945 0.3048)
			(stroke
				(width 0.1)
				(type default)
			)
			(layer "F.Fab")
		)
		(fp_line
			(start 0.67945 0.3048)
			(end 0.120396 0.3048)
			(stroke
				(width 0.1)
				(type default)
			)
			(layer "F.Fab")
		)
		(pad "1" smd circle
			(at -0.40005 0)
			(size 0 0)
			(layers "F.Cu" "F.Mask" "F.Paste")
			(net "SMB_LM75_3_3V3AUX_SDA_R")
		)
		(pad "2" smd circle
			(at 0.40005 0)
			(size 0 0)
			(layers "F.Cu" "F.Mask" "F.Paste")
			(net "SMB_LM75_3_3V3AUX_SDA")
		)
	)
	(footprint ""
		(layer "F.Cu")
		(at 309.522622 -33.772348 180)
		(property "Reference" "R1600"
			(at 0 0 180)
			(layer "F.SilkS")
			(hide yes)
			(effects
				(font
					(size 1.27 1.27)
				)
			)
		)
		(property "Value" ""
			(at 0 0 180)
			(layer "F.Fab")
			(effects
				(font
					(size 1.27 1.27)
				)
			)
		)
		(duplicate_pad_numbers_are_jumpers no)
		(fp_line
			(start 0.7874 0.4064)
			(end -0.7874 0.4064)
			(stroke
				(width 0.1524)
				(type default)
			)
			(layer "F.SilkS")
		)
		(fp_line
			(start 0.7874 -0.4064)
			(end 0.7874 0.4064)
			(stroke
				(width 0.1524)
				(type default)
			)
			(layer "F.SilkS")
		)
		(fp_line
			(start -0.7874 0.4064)
			(end -0.7874 -0.4064)
			(stroke
				(width 0.1524)
				(type default)
			)
			(layer "F.SilkS")
		)
		(fp_line
			(start -0.7874 -0.4064)
			(end 0.7874 -0.4064)
			(stroke
				(width 0.1524)
				(type default)
			)
			(layer "F.SilkS")
		)
		(fp_line
			(start 0.67945 0.3048)
			(end 0.120396 0.3048)
			(stroke
				(width 0.1)
				(type default)
			)
			(layer "F.Fab")
		)
		(fp_line
			(start 0.67945 -0.3048)
			(end 0.67945 0.3048)
			(stroke
				(width 0.1)
				(type default)
			)
			(layer "F.Fab")
		)
		(fp_line
			(start 0.12065 -0.2794)
			(end 0.12065 -0.3048)
			(stroke
				(width 0.1)
				(type default)
			)
			(layer "F.Fab")
		)
		(fp_line
			(start 0.12065 -0.3048)
			(end 0.67945 -0.3048)
			(stroke
				(width 0.1)
				(type default)
			)
			(layer "F.Fab")
		)
		(fp_line
			(start 0.120396 0.3048)
			(end 0.120396 0.2794)
			(stroke
				(width 0.1)
				(type default)
			)
			(layer "F.Fab")
		)
		(fp_line
			(start 0.120396 0.2794)
			(end -0.12065 0.2794)
			(stroke
				(width 0.1)
				(type default)
			)
			(layer "F.Fab")
		)
		(fp_line
			(start -0.12065 0.3048)
			(end -0.67945 0.3048)
			(stroke
				(width 0.1)
				(type default)
			)
			(layer "F.Fab")
		)
		(fp_line
			(start -0.12065 0.2794)
			(end -0.12065 0.3048)
			(stroke
				(width 0.1)
				(type default)
			)
			(layer "F.Fab")
		)
		(fp_line
			(start -0.12065 -0.2794)
			(end 0.12065 -0.2794)
			(stroke
				(width 0.1)
				(type default)
			)
			(layer "F.Fab")
		)
		(fp_line
			(start -0.12065 -0.305054)
			(end -0.12065 -0.2794)
			(stroke
				(width 0.1)
				(type default)
			)
			(layer "F.Fab")
		)
		(fp_line
			(start -0.67945 0.3048)
			(end -0.67945 -0.305054)
			(stroke
				(width 0.1)
				(type default)
			)
			(layer "F.Fab")
		)
		(fp_line
			(start -0.67945 -0.305054)
			(end -0.12065 -0.305054)
			(stroke
				(width 0.1)
				(type default)
			)
			(layer "F.Fab")
		)
		(pad "1" smd circle
			(at -0.40005 0 180)
			(size 0 0)
			(layers "F.Cu" "F.Mask" "F.Paste")
			(net "IRQ_SML0_ALERT_N")
		)
		(pad "2" smd circle
			(at 0.40005 0 180)
			(size 0 0)
			(layers "F.Cu" "F.Mask" "F.Paste")
			(net "IRQ_SML0_ALERT_R_N")
		)
	)
)
